(kicad_pcb
	(version 20260206)
	(generator "pcbnew")
	(generator_version "10.0")
	(general
		(thickness 1.6)
		(legacy_teardrops no)
	)
	(paper "A4")
	(title_block
		(title "Bryce Canyon_F.DPB_16315-1-OCP.brd")
		(comment 1 "Bryce Canyon / footprint 939 of 2223 (DPB1), pads 1-73 of 150")
	)
	(layers
		(0 "F.Cu" signal "TOP")
		(4 "In1.Cu" signal "L2GND")
		(6 "In2.Cu" signal "L3")
		(8 "In3.Cu" signal "L4GND")
		(10 "In4.Cu" signal "L5")
		(12 "In5.Cu" signal "L6VCC")
		(14 "In6.Cu" signal "L7VCC")
		(16 "In7.Cu" signal "L8")
		(18 "In8.Cu" signal "L9GND")
		(20 "In9.Cu" signal "L10")
		(22 "In10.Cu" signal "L11GND")
		(2 "B.Cu" signal "BOTTOM")
		(9 "F.Adhes" user "F.Adhesive")
		(11 "B.Adhes" user "B.Adhesive")
		(13 "F.Paste" user "Package Geometry/Pastemask Top")
		(15 "B.Paste" user "Package Geometry/Pastemask Bottom")
		(5 "F.SilkS" user "Ref Des/Silkscreen Top")
		(7 "B.SilkS" user "Ref Des/Silkscreen Bottom")
		(1 "F.Mask" user "Board Geometry/Soldermask Top")
		(3 "B.Mask" user "Board Geometry/Soldermask Bottom")
		(17 "Dwgs.User" user "User.Drawings")
		(19 "Cmts.User" user "User.Comments")
		(21 "Eco1.User" user "User.Eco1")
		(23 "Eco2.User" user "User.Eco2")
		(25 "Edge.Cuts" user "Board Geometry/Outline")
		(27 "Margin" user)
		(31 "F.CrtYd" user "Package Geometry/Place Bound Top")
		(29 "B.CrtYd" user "Package Geometry/Place Bound Bottom")
		(35 "F.Fab" user "Ref Des/Assembly Top")
		(33 "B.Fab" user "Ref Des/Assembly Bottom")
	)
	(footprint ""
		(layer "F.Cu")
		(at 210.000088 -419.200076)
		(property "Reference" "DPB1"
			(at 0 0 0)
			(layer "F.SilkS")
			(hide yes)
			(effects
				(font
					(size 1.27 1.27)
				)
			)
		)
		(property "Value" "AMP-CONN150-12R-4-GP"
			(at -12.8016 -12.1412 0)
			(unlocked yes)
			(layer "F.Fab")
			(hide yes)
			(effects
				(font
					(size 1.016 1.016)
					(thickness 0.1524)
				)
			)
		)
		(property "Device Type" "PREFIT-150P-258346H582"
			(at -12.8016 -13.6652 0)
			(unlocked yes)
			(layer "F.Fab")
			(hide yes)
			(effects
				(font
					(size 1.016 1.016)
					(thickness 0.1524)
				)
			)
		)
		(duplicate_pad_numbers_are_jumpers no)
		(pad "A1" thru_hole circle
			(at 0 0)
			(size 0.762 0.762)
			(drill 0.359918)
			(layers "*.Cu" "*.Mask")
			(remove_unused_layers no)
			(net "PWM_BMC_B_ZONE_C")
			(clearance 0.1651)
			(thermal_gap 0.1651)
		)
		(pad "A2" thru_hole circle
			(at 1.800098 0.999998)
			(size 0.762 0.762)
			(drill 0.359918)
			(layers "*.Cu" "*.Mask")
			(remove_unused_layers no)
			(net "PCIE_COMP_B_TO_SCC_B_1_DP")
			(clearance 0.1651)
			(thermal_gap 0.1651)
		)
		(pad "A3" thru_hole circle
			(at 3.599942 0)
			(size 0.762 0.762)
			(drill 0.359918)
			(layers "*.Cu" "*.Mask")
			(remove_unused_layers no)
			(net "I2C_DPB_B_SCL")
			(clearance 0.1651)
			(thermal_gap 0.1651)
		)
		(pad "A4" thru_hole circle
			(at 5.40004 0.999998)
			(size 0.762 0.762)
			(drill 0.359918)
			(layers "*.Cu" "*.Mask")
			(remove_unused_layers no)
			(net "PCIE_COMP_B_TO_SCC_B_3_DP")
			(clearance 0.1651)
			(thermal_gap 0.1651)
		)
		(pad "A5" thru_hole circle
			(at 7.199884 0)
			(size 0.762 0.762)
			(drill 0.359918)
			(layers "*.Cu" "*.Mask")
			(remove_unused_layers no)
			(net "I2C_BMC_A_EXP_B_SCL")
			(clearance 0.1651)
			(thermal_gap 0.1651)
		)
		(pad "A6" thru_hole circle
			(at 8.999982 0.999998)
			(size 0.762 0.762)
			(drill 0.359918)
			(layers "*.Cu" "*.Mask")
			(remove_unused_layers no)
			(net "PCIE_COMP_B_TO_SCC_B_5_DP")
			(clearance 0.1651)
			(thermal_gap 0.1651)
		)
		(pad "A7" thru_hole circle
			(at 10.80008 0)
			(size 0.762 0.762)
			(drill 0.359918)
			(layers "*.Cu" "*.Mask")
			(remove_unused_layers no)
			(net "UART_EXP_B_TX")
			(clearance 0.1651)
			(thermal_gap 0.1651)
		)
		(pad "A8" thru_hole circle
			(at 12.599924 0.999998)
			(size 0.762 0.762)
			(drill 0.359918)
			(layers "*.Cu" "*.Mask")
			(remove_unused_layers no)
			(net "PCIE_COMP_B_TO_SCC_B_7_DP")
			(clearance 0.1651)
			(thermal_gap 0.1651)
		)
		(pad "A9" thru_hole circle
			(at 16.20012 0)
			(size 0.762 0.762)
			(drill 0.359918)
			(layers "*.Cu" "*.Mask")
			(remove_unused_layers no)
			(net "SCC_B_STBY_PGOOD")
			(clearance 0.1651)
			(thermal_gap 0.1651)
		)
		(pad "A10" thru_hole circle
			(at 17.999964 -0.100076)
			(size 0.762 0.762)
			(drill 0.359918)
			(layers "*.Cu" "*.Mask")
			(remove_unused_layers no)
			(net "SCC_B_PWR_LED")
			(clearance 0.1651)
			(thermal_gap 0.1651)
		)
		(pad "A11" thru_hole circle
			(at 19.800062 0)
			(size 0.762 0.762)
			(drill 0.359918)
			(layers "*.Cu" "*.Mask")
			(remove_unused_layers no)
			(net "DRIVE_B_24_ACT")
			(clearance 0.1651)
			(thermal_gap 0.1651)
		)
		(pad "A12" thru_hole circle
			(at 21.599906 -0.100076)
			(size 0.762 0.762)
			(drill 0.359918)
			(layers "*.Cu" "*.Mask")
			(remove_unused_layers no)
			(net "BMC_B_EXP_B_SPARE_0")
			(clearance 0.1651)
			(thermal_gap 0.1651)
		)
		(pad "B1" thru_hole circle
			(at 0 1.400048)
			(size 0.762 0.762)
			(drill 0.359918)
			(layers "*.Cu" "*.Mask")
			(remove_unused_layers no)
			(net "PWM_BMC_B_ZONE_D")
			(clearance 0.1651)
			(thermal_gap 0.1651)
		)
		(pad "B2" thru_hole circle
			(at 1.800098 2.400046)
			(size 0.762 0.762)
			(drill 0.359918)
			(layers "*.Cu" "*.Mask")
			(remove_unused_layers no)
			(net "PCIE_COMP_B_TO_SCC_B_1_DN")
			(clearance 0.1651)
			(thermal_gap 0.1651)
		)
		(pad "B3" thru_hole circle
			(at 3.599942 1.400048)
			(size 0.762 0.762)
			(drill 0.359918)
			(layers "*.Cu" "*.Mask")
			(remove_unused_layers no)
			(net "I2C_DPB_B_SDA")
			(clearance 0.1651)
			(thermal_gap 0.1651)
		)
		(pad "B4" thru_hole circle
			(at 5.40004 2.400046)
			(size 0.762 0.762)
			(drill 0.359918)
			(layers "*.Cu" "*.Mask")
			(remove_unused_layers no)
			(net "PCIE_COMP_B_TO_SCC_B_3_DN")
			(clearance 0.1651)
			(thermal_gap 0.1651)
		)
		(pad "B5" thru_hole circle
			(at 7.199884 1.400048)
			(size 0.762 0.762)
			(drill 0.359918)
			(layers "*.Cu" "*.Mask")
			(remove_unused_layers no)
			(net "I2C_BMC_A_EXP_B_SDA")
			(clearance 0.1651)
			(thermal_gap 0.1651)
		)
		(pad "B6" thru_hole circle
			(at 8.999982 2.400046)
			(size 0.762 0.762)
			(drill 0.359918)
			(layers "*.Cu" "*.Mask")
			(remove_unused_layers no)
			(net "PCIE_COMP_B_TO_SCC_B_5_DN")
			(clearance 0.1651)
			(thermal_gap 0.1651)
		)
		(pad "B7" thru_hole circle
			(at 10.80008 1.400048)
			(size 0.762 0.762)
			(drill 0.359918)
			(layers "*.Cu" "*.Mask")
			(remove_unused_layers no)
			(net "UART_EXP_B_RX")
			(clearance 0.1651)
			(thermal_gap 0.1651)
		)
		(pad "B8" thru_hole circle
			(at 12.599924 2.400046)
			(size 0.762 0.762)
			(drill 0.359918)
			(layers "*.Cu" "*.Mask")
			(remove_unused_layers no)
			(net "PCIE_COMP_B_TO_SCC_B_7_DN")
			(clearance 0.1651)
			(thermal_gap 0.1651)
		)
		(pad "B9" thru_hole circle
			(at 16.20012 1.400048)
			(size 0.762 0.762)
			(drill 0.359918)
			(layers "*.Cu" "*.Mask")
			(remove_unused_layers no)
			(net "SCC_A_FULL_PWR_EN")
			(clearance 0.1651)
			(thermal_gap 0.1651)
		)
		(pad "B10" thru_hole circle
			(at 17.999964 0.999998)
			(size 0.762 0.762)
			(drill 0.359918)
			(layers "*.Cu" "*.Mask")
			(remove_unused_layers no)
			(net "FAN_0_INS_N")
			(clearance 0.1651)
			(thermal_gap 0.1651)
		)
		(pad "B11" thru_hole circle
			(at 19.800062 1.400048)
			(size 0.762 0.762)
			(drill 0.359918)
			(layers "*.Cu" "*.Mask")
			(remove_unused_layers no)
			(net "DRIVE_B_25_ACT")
			(clearance 0.1651)
			(thermal_gap 0.1651)
		)
		(pad "B12" thru_hole circle
			(at 21.599906 0.999998)
			(size 0.762 0.762)
			(drill 0.359918)
			(layers "*.Cu" "*.Mask")
			(remove_unused_layers no)
			(net "BMC_B_EXP_B_SPARE_1")
			(clearance 0.1651)
			(thermal_gap 0.1651)
		)
		(pad "C1" thru_hole circle
			(at 0 3.599942)
			(size 0.762 0.762)
			(drill 0.359918)
			(layers "*.Cu" "*.Mask")
			(remove_unused_layers no)
			(net "PCIE_COMP_B_TO_SCC_B_0_DP")
			(clearance 0.1651)
			(thermal_gap 0.1651)
		)
		(pad "C2" thru_hole circle
			(at 1.800098 4.59994)
			(size 0.762 0.762)
			(drill 0.359918)
			(layers "*.Cu" "*.Mask")
			(remove_unused_layers no)
			(net "I2C_SCC_B_SCL")
			(clearance 0.1651)
			(thermal_gap 0.1651)
		)
		(pad "C3" thru_hole circle
			(at 3.599942 3.599942)
			(size 0.762 0.762)
			(drill 0.359918)
			(layers "*.Cu" "*.Mask")
			(remove_unused_layers no)
			(net "PCIE_COMP_B_TO_SCC_B_2_DP")
			(clearance 0.1651)
			(thermal_gap 0.1651)
		)
		(pad "C4" thru_hole circle
			(at 5.40004 4.59994)
			(size 0.762 0.762)
			(drill 0.359918)
			(layers "*.Cu" "*.Mask")
			(remove_unused_layers no)
			(net "PWM_BMC_A_ZONE_C")
			(clearance 0.1651)
			(thermal_gap 0.1651)
		)
		(pad "C5" thru_hole circle
			(at 7.199884 3.599942)
			(size 0.762 0.762)
			(drill 0.359918)
			(layers "*.Cu" "*.Mask")
			(remove_unused_layers no)
			(net "PCIE_COMP_B_TO_SCC_B_4_DP")
			(clearance 0.1651)
			(thermal_gap 0.1651)
		)
		(pad "C6" thru_hole circle
			(at 8.999982 4.59994)
			(size 0.762 0.762)
			(drill 0.359918)
			(layers "*.Cu" "*.Mask")
			(remove_unused_layers no)
			(net "I2C_DRIVE_B_FLT_LED_SDA")
			(clearance 0.1651)
			(thermal_gap 0.1651)
		)
		(pad "C7" thru_hole circle
			(at 10.80008 3.599942)
			(size 0.762 0.762)
			(drill 0.359918)
			(layers "*.Cu" "*.Mask")
			(remove_unused_layers no)
			(net "PCIE_COMP_B_TO_SCC_B_6_DP")
			(clearance 0.1651)
			(thermal_gap 0.1651)
		)
		(pad "C8" thru_hole circle
			(at 12.599924 4.59994)
			(size 0.762 0.762)
			(drill 0.359918)
			(layers "*.Cu" "*.Mask")
			(remove_unused_layers no)
			(net "UART_IOC_B_TX")
			(clearance 0.1651)
			(thermal_gap 0.1651)
		)
		(pad "C9" thru_hole circle
			(at 16.20012 2.500122)
			(size 0.762 0.762)
			(drill 0.359918)
			(layers "*.Cu" "*.Mask")
			(remove_unused_layers no)
			(net "SCC_B_FULL_PWR_EN")
			(clearance 0.1651)
			(thermal_gap 0.1651)
		)
		(pad "C10" thru_hole circle
			(at 17.999964 2.400046)
			(size 0.762 0.762)
			(drill 0.359918)
			(layers "*.Cu" "*.Mask")
			(remove_unused_layers no)
			(net "FAN_1_INS_N")
			(clearance 0.1651)
			(thermal_gap 0.1651)
		)
		(pad "C11" thru_hole circle
			(at 19.800062 2.500122)
			(size 0.762 0.762)
			(drill 0.359918)
			(layers "*.Cu" "*.Mask")
			(remove_unused_layers no)
			(net "DRIVE_B_26_ACT")
			(clearance 0.1651)
			(thermal_gap 0.1651)
		)
		(pad "C12" thru_hole circle
			(at 21.599906 2.400046)
			(size 0.762 0.762)
			(drill 0.359918)
			(layers "*.Cu" "*.Mask")
			(remove_unused_layers no)
			(net "BMC_A_HEARTBEAT")
			(clearance 0.1651)
			(thermal_gap 0.1651)
		)
		(pad "D1" thru_hole circle
			(at 0 4.99999)
			(size 0.762 0.762)
			(drill 0.359918)
			(layers "*.Cu" "*.Mask")
			(remove_unused_layers no)
			(net "PCIE_COMP_B_TO_SCC_B_0_DN")
			(clearance 0.1651)
			(thermal_gap 0.1651)
		)
		(pad "D2" thru_hole circle
			(at 1.800098 5.999988)
			(size 0.762 0.762)
			(drill 0.359918)
			(layers "*.Cu" "*.Mask")
			(remove_unused_layers no)
			(net "I2C_SCC_B_SDA")
			(clearance 0.1651)
			(thermal_gap 0.1651)
		)
		(pad "D3" thru_hole circle
			(at 3.599942 4.99999)
			(size 0.762 0.762)
			(drill 0.359918)
			(layers "*.Cu" "*.Mask")
			(remove_unused_layers no)
			(net "PCIE_COMP_B_TO_SCC_B_2_DN")
			(clearance 0.1651)
			(thermal_gap 0.1651)
		)
		(pad "D4" thru_hole circle
			(at 5.40004 5.999988)
			(size 0.762 0.762)
			(drill 0.359918)
			(layers "*.Cu" "*.Mask")
			(remove_unused_layers no)
			(net "PWM_BMC_A_ZONE_D")
			(clearance 0.1651)
			(thermal_gap 0.1651)
		)
		(pad "D5" thru_hole circle
			(at 7.199884 4.99999)
			(size 0.762 0.762)
			(drill 0.359918)
			(layers "*.Cu" "*.Mask")
			(remove_unused_layers no)
			(net "PCIE_COMP_B_TO_SCC_B_4_DN")
			(clearance 0.1651)
			(thermal_gap 0.1651)
		)
		(pad "D6" thru_hole circle
			(at 8.999982 5.999988)
			(size 0.762 0.762)
			(drill 0.359918)
			(layers "*.Cu" "*.Mask")
			(remove_unused_layers no)
			(net "I2C_DRIVE_B_FLT_LED_SCL")
			(clearance 0.1651)
			(thermal_gap 0.1651)
		)
		(pad "D7" thru_hole circle
			(at 10.80008 4.99999)
			(size 0.762 0.762)
			(drill 0.359918)
			(layers "*.Cu" "*.Mask")
			(remove_unused_layers no)
			(net "PCIE_COMP_B_TO_SCC_B_6_DN")
			(clearance 0.1651)
			(thermal_gap 0.1651)
		)
		(pad "D8" thru_hole circle
			(at 12.599924 5.999988)
			(size 0.762 0.762)
			(drill 0.359918)
			(layers "*.Cu" "*.Mask")
			(remove_unused_layers no)
			(net "UART_IOC_B_RX")
			(clearance 0.1651)
			(thermal_gap 0.1651)
		)
		(pad "D9" thru_hole circle
			(at 16.20012 3.599942)
			(size 0.762 0.762)
			(drill 0.359918)
			(layers "*.Cu" "*.Mask")
			(remove_unused_layers no)
			(net "SCC_B_FULL_PGOOD")
			(clearance 0.1651)
			(thermal_gap 0.1651)
		)
		(pad "D10" thru_hole circle
			(at 17.999964 3.50012)
			(size 0.762 0.762)
			(drill 0.359918)
			(layers "*.Cu" "*.Mask")
			(remove_unused_layers no)
			(net "FAN_2_INS_N")
			(clearance 0.1651)
			(thermal_gap 0.1651)
		)
		(pad "D11" thru_hole circle
			(at 19.800062 3.599942)
			(size 0.762 0.762)
			(drill 0.359918)
			(layers "*.Cu" "*.Mask")
			(remove_unused_layers no)
			(net "DRIVE_B_27_ACT")
			(clearance 0.1651)
			(thermal_gap 0.1651)
		)
		(pad "D12" thru_hole circle
			(at 21.599906 3.50012)
			(size 0.762 0.762)
			(drill 0.359918)
			(layers "*.Cu" "*.Mask")
			(remove_unused_layers no)
			(net "BMC_B_HEARTBEAT")
			(clearance 0.1651)
			(thermal_gap 0.1651)
		)
		(pad "E1" thru_hole circle
			(at 0 7.199884)
			(size 0.762 0.762)
			(drill 0.359918)
			(layers "*.Cu" "*.Mask")
			(remove_unused_layers no)
			(net "PCIE_COMP_B_TO_SCC_B_CLK_0_DP")
			(clearance 0.1651)
			(thermal_gap 0.1651)
		)
		(pad "E2" thru_hole circle
			(at 1.800098 8.199882)
			(size 0.762 0.762)
			(drill 0.359918)
			(layers "*.Cu" "*.Mask")
			(remove_unused_layers no)
			(net "I2C_DPB_A_SCL_BUF")
			(clearance 0.1651)
			(thermal_gap 0.1651)
		)
		(pad "E3" thru_hole circle
			(at 3.599942 7.199884)
			(size 0.762 0.762)
			(drill 0.359918)
			(layers "*.Cu" "*.Mask")
			(remove_unused_layers no)
			(net "I2C_CLIP_A_SCL")
			(clearance 0.1651)
			(thermal_gap 0.1651)
		)
		(pad "E4" thru_hole circle
			(at 5.40004 8.199882)
			(size 0.762 0.762)
			(drill 0.359918)
			(layers "*.Cu" "*.Mask")
			(remove_unused_layers no)
			(net "COMP_B_EXP_B_SPARE_0")
			(clearance 0.1651)
			(thermal_gap 0.1651)
		)
		(pad "E5" thru_hole circle
			(at 7.199884 7.199884)
			(size 0.762 0.762)
			(drill 0.359918)
			(layers "*.Cu" "*.Mask")
			(remove_unused_layers no)
			(net "I2C_BMC_B_EXP_B_SCL")
			(clearance 0.1651)
			(thermal_gap 0.1651)
		)
		(pad "E6" thru_hole circle
			(at 8.999982 8.199882)
			(size 0.762 0.762)
			(drill 0.359918)
			(layers "*.Cu" "*.Mask")
			(remove_unused_layers no)
			(net "Net_57")
			(clearance 0.1651)
			(thermal_gap 0.1651)
		)
		(pad "E7" thru_hole circle
			(at 10.80008 7.199884)
			(size 0.762 0.762)
			(drill 0.359918)
			(layers "*.Cu" "*.Mask")
			(remove_unused_layers no)
			(net "UART_SDB_B_RX")
			(clearance 0.1651)
			(thermal_gap 0.1651)
		)
		(pad "E8" thru_hole circle
			(at 12.599924 8.199882)
			(size 0.762 0.762)
			(drill 0.359918)
			(layers "*.Cu" "*.Mask")
			(remove_unused_layers no)
			(net "PWM_SCC_A_ZONE_C")
			(clearance 0.1651)
			(thermal_gap 0.1651)
		)
		(pad "E9" thru_hole circle
			(at 16.20012 4.99999)
			(size 0.762 0.762)
			(drill 0.359918)
			(layers "*.Cu" "*.Mask")
			(remove_unused_layers no)
			(net "DRAWER_CLOSED_N")
			(clearance 0.1651)
			(thermal_gap 0.1651)
		)
		(pad "E10" thru_hole circle
			(at 17.999964 4.59994)
			(size 0.762 0.762)
			(drill 0.359918)
			(layers "*.Cu" "*.Mask")
			(remove_unused_layers no)
			(net "FAN_3_INS_N")
			(clearance 0.1651)
			(thermal_gap 0.1651)
		)
		(pad "E11" thru_hole circle
			(at 19.800062 4.99999)
			(size 0.762 0.762)
			(drill 0.359918)
			(layers "*.Cu" "*.Mask")
			(remove_unused_layers no)
			(net "DRIVE_B_28_ACT")
			(clearance 0.1651)
			(thermal_gap 0.1651)
		)
		(pad "E12" thru_hole circle
			(at 21.599906 4.59994)
			(size 0.762 0.762)
			(drill 0.359918)
			(layers "*.Cu" "*.Mask")
			(remove_unused_layers no)
			(net "SCC_A_HEARTBEAT")
			(clearance 0.1651)
			(thermal_gap 0.1651)
		)
		(pad "F1" thru_hole circle
			(at 0 8.599932)
			(size 0.762 0.762)
			(drill 0.359918)
			(layers "*.Cu" "*.Mask")
			(remove_unused_layers no)
			(net "PCIE_COMP_B_TO_SCC_B_CLK_0_DN")
			(clearance 0.1651)
			(thermal_gap 0.1651)
		)
		(pad "F2" thru_hole circle
			(at 1.800098 9.59993)
			(size 0.762 0.762)
			(drill 0.359918)
			(layers "*.Cu" "*.Mask")
			(remove_unused_layers no)
			(net "I2C_DPB_A_SDA_BUF")
			(clearance 0.1651)
			(thermal_gap 0.1651)
		)
		(pad "F3" thru_hole circle
			(at 3.599942 8.599932)
			(size 0.762 0.762)
			(drill 0.359918)
			(layers "*.Cu" "*.Mask")
			(remove_unused_layers no)
			(net "I2C_CLIP_A_SDA")
			(clearance 0.1651)
			(thermal_gap 0.1651)
		)
		(pad "F4" thru_hole circle
			(at 5.40004 9.59993)
			(size 0.762 0.762)
			(drill 0.359918)
			(layers "*.Cu" "*.Mask")
			(remove_unused_layers no)
			(net "PCIE_COMP_B_TO_SCC_B_RST_0")
			(clearance 0.1651)
			(thermal_gap 0.1651)
		)
		(pad "F5" thru_hole circle
			(at 7.199884 8.599932)
			(size 0.762 0.762)
			(drill 0.359918)
			(layers "*.Cu" "*.Mask")
			(remove_unused_layers no)
			(net "I2C_BMC_B_EXP_B_SDA")
			(clearance 0.1651)
			(thermal_gap 0.1651)
		)
		(pad "F6" thru_hole circle
			(at 8.999982 9.59993)
			(size 0.762 0.762)
			(drill 0.359918)
			(layers "*.Cu" "*.Mask")
			(remove_unused_layers no)
			(net "SCC_B_RESET_N")
			(clearance 0.1651)
			(thermal_gap 0.1651)
		)
		(pad "F7" thru_hole circle
			(at 10.80008 8.599932)
			(size 0.762 0.762)
			(drill 0.359918)
			(layers "*.Cu" "*.Mask")
			(remove_unused_layers no)
			(net "UART_SDB_B_TX")
			(clearance 0.1651)
			(thermal_gap 0.1651)
		)
		(pad "F8" thru_hole circle
			(at 12.599924 9.59993)
			(size 0.762 0.762)
			(drill 0.359918)
			(layers "*.Cu" "*.Mask")
			(remove_unused_layers no)
			(net "PWM_SCC_A_ZONE_D")
			(clearance 0.1651)
			(thermal_gap 0.1651)
		)
		(pad "F9" thru_hole circle
			(at 16.20012 6.100064)
			(size 0.762 0.762)
			(drill 0.359918)
			(layers "*.Cu" "*.Mask")
			(remove_unused_layers no)
			(net "P12V_IN_PGOOD")
			(clearance 0.1651)
			(thermal_gap 0.1651)
		)
		(pad "F10" thru_hole circle
			(at 17.999964 5.999988)
			(size 0.762 0.762)
			(drill 0.359918)
			(layers "*.Cu" "*.Mask")
			(remove_unused_layers no)
			(net "IOM_A_INS_N")
			(clearance 0.1651)
			(thermal_gap 0.1651)
		)
		(pad "F11" thru_hole circle
			(at 19.800062 6.100064)
			(size 0.762 0.762)
			(drill 0.359918)
			(layers "*.Cu" "*.Mask")
			(remove_unused_layers no)
			(net "DRIVE_B_29_ACT")
			(clearance 0.1651)
			(thermal_gap 0.1651)
		)
		(pad "F12" thru_hole circle
			(at 21.599906 5.999988)
			(size 0.762 0.762)
			(drill 0.359918)
			(layers "*.Cu" "*.Mask")
			(remove_unused_layers no)
			(net "SCC_B_HEARTBEAT")
			(clearance 0.1651)
			(thermal_gap 0.1651)
		)
		(pad "G1" thru_hole circle
			(at 0 10.80008)
			(size 0.762 0.762)
			(drill 0.359918)
			(layers "*.Cu" "*.Mask")
			(remove_unused_layers no)
			(net "PCIE_SCC_B_TO_COMP_B_0_DP")
			(clearance 0.1651)
			(thermal_gap 0.1651)
		)
	)
)
